(kicad_pcb
	(version 20260206)
	(generator "pcbnew")
	(generator_version "10.0")
	(general
		(thickness 1.6)
		(legacy_teardrops no)
	)
	(paper "A4")
	(title_block
		(title "dpb — 14545-sa.0730WZS0815.brd")
		(comment 1 "Honey Badger (Wiwynn) / footprints 307-314 of 1066")
	)
	(layers
		(0 "F.Cu" signal "TOP")
		(4 "In1.Cu" signal "L2GND")
		(6 "In2.Cu" signal "L3")
		(8 "In3.Cu" signal "L4VCC")
		(10 "In4.Cu" signal "L5VCC")
		(12 "In5.Cu" signal "L6")
		(14 "In6.Cu" signal "L7GND")
		(2 "B.Cu" signal "BOTTOM")
		(9 "F.Adhes" user "F.Adhesive")
		(11 "B.Adhes" user "B.Adhesive")
		(13 "F.Paste" user "Package Geometry/Pastemask Top")
		(15 "B.Paste" user "Package Geometry/Pastemask Bottom")
		(5 "F.SilkS" user "Ref Des/Silkscreen Top")
		(7 "B.SilkS" user "Ref Des/Silkscreen Bottom")
		(1 "F.Mask" user "Board Geometry/Soldermask Top")
		(3 "B.Mask" user "Board Geometry/Soldermask Bottom")
		(17 "Dwgs.User" user "User.Drawings")
		(19 "Cmts.User" user "User.Comments")
		(21 "Eco1.User" user "User.Eco1")
		(23 "Eco2.User" user "User.Eco2")
		(25 "Edge.Cuts" user "Board Geometry/Outline")
		(27 "Margin" user)
		(31 "F.CrtYd" user "Package Geometry/Place Bound Top")
		(29 "B.CrtYd" user "Package Geometry/Place Bound Bottom")
		(35 "F.Fab" user "Ref Des/Assembly Top")
		(33 "B.Fab" user "Ref Des/Assembly Bottom")
	)
	(footprint ""
		(layer "F.Cu")
		(at 44.246546 -131.7879 180)
		(property "Reference" "R317"
			(at 0 0 180)
			(layer "F.SilkS")
			(hide yes)
			(effects
				(font
					(size 1.27 1.27)
				)
			)
		)
		(property "Value" "4K7R2J-2-GP"
			(at 0.064008 -3.993896 180)
			(unlocked yes)
			(layer "F.Fab")
			(hide yes)
			(effects
				(font
					(size 1.016 1.016)
					(thickness 0.1524)
				)
			)
		)
		(property "Device Type" "R402H16"
			(at 0.064008 -5.517896 180)
			(unlocked yes)
			(layer "F.Fab")
			(hide yes)
			(effects
				(font
					(size 1.016 1.016)
					(thickness 0.1524)
				)
			)
		)
		(duplicate_pad_numbers_are_jumpers no)
		(fp_line
			(start 0.508 -0.9398)
			(end -0.508 -0.9398)
			(stroke
				(width 0.1524)
				(type default)
			)
			(layer "F.SilkS")
		)
		(fp_line
			(start -0.508 -0.9398)
			(end -0.508 0.9398)
			(stroke
				(width 0.1524)
				(type default)
			)
			(layer "F.SilkS")
		)
		(fp_rect
			(start -0.508 0.9398)
			(end 0.508 -0.9398)
			(stroke
				(width 0)
				(type default)
			)
			(fill no)
			(layer "F.CrtYd")
		)
		(fp_rect
			(start -0.508 0.9398)
			(end 0.508 -0.9398)
			(stroke
				(width 0)
				(type default)
			)
			(fill no)
			(layer "F.Fab")
		)
		(pad "1" smd custom
			(at 0 -0.4445 180)
			(size 0.1397 0.1397)
			(layers "F.Cu" "F.Mask" "F.Paste")
			(net "P3V3")
			(options
				(clearance outline)
				(anchor circle)
			)
			(primitives
				(gr_poly
					(pts
						(arc
							(start -0.1778 -0.2794)
							(mid -0.249642 -0.249642)
							(end -0.2794 -0.1778)
						)
						(arc
							(start -0.2794 0.1778)
							(mid -0.249642 0.249642)
							(end -0.1778 0.2794)
						)
						(arc
							(start 0.1778 0.2794)
							(mid 0.249642 0.249642)
							(end 0.2794 0.1778)
						)
						(arc
							(start 0.2794 -0.1778)
							(mid 0.249642 -0.249642)
							(end 0.1778 -0.2794)
						)
					)
					(width 0)
					(fill yes)
				)
			)
		)
		(pad "2" smd custom
			(at 0 0.4445 180)
			(size 0.1397 0.1397)
			(layers "F.Cu" "F.Mask" "F.Paste")
			(net "I2C_B_TMP2_A0")
			(options
				(clearance outline)
				(anchor circle)
			)
			(primitives
				(gr_poly
					(pts
						(arc
							(start -0.1778 -0.2794)
							(mid -0.249642 -0.249642)
							(end -0.2794 -0.1778)
						)
						(arc
							(start -0.2794 0.1778)
							(mid -0.249642 0.249642)
							(end -0.1778 0.2794)
						)
						(arc
							(start 0.1778 0.2794)
							(mid 0.249642 0.249642)
							(end 0.2794 0.1778)
						)
						(arc
							(start 0.2794 -0.1778)
							(mid 0.249642 -0.249642)
							(end 0.1778 -0.2794)
						)
					)
					(width 0)
					(fill yes)
				)
			)
		)
	)
	(footprint ""
		(layer "F.Cu")
		(at 223.4565 -434.136546)
		(property "Reference" "U54"
			(at 0 0 0)
			(layer "F.SilkS")
			(hide yes)
			(effects
				(font
					(size 1.27 1.27)
				)
			)
		)
		(property "Value" "SY8201ABC-GP"
			(at -0.0254 -11.9634 0)
			(unlocked yes)
			(layer "F.Fab")
			(hide yes)
			(effects
				(font
					(size 1.016 1.016)
					(thickness 0.1524)
				)
			)
		)
		(property "Device Type" "SOT-6H56"
			(at -0.0254 -13.5636 0)
			(unlocked yes)
			(layer "F.Fab")
			(hide yes)
			(effects
				(font
					(size 1.016 1.016)
					(thickness 0.1524)
				)
			)
		)
		(duplicate_pad_numbers_are_jumpers no)
		(fp_line
			(start -1.9685 -0.5842)
			(end -1.9685 0.5842)
			(stroke
				(width 0.1524)
				(type default)
			)
			(layer "F.SilkS")
		)
		(fp_line
			(start -1.9685 -0.4064)
			(end -1.5621 0)
			(stroke
				(width 0.1524)
				(type default)
			)
			(layer "F.SilkS")
		)
		(fp_line
			(start -1.9685 0.5842)
			(end -1.9685 2.3622)
			(stroke
				(width 0.508)
				(type default)
			)
			(layer "F.SilkS")
		)
		(fp_line
			(start -1.9685 0.5842)
			(end 1.7145 0.5842)
			(stroke
				(width 0.1524)
				(type default)
			)
			(layer "F.SilkS")
		)
		(fp_line
			(start -1.5621 0)
			(end -1.9685 0.4064)
			(stroke
				(width 0.1524)
				(type default)
			)
			(layer "F.SilkS")
		)
		(fp_line
			(start 1.7145 -0.5842)
			(end -1.9685 -0.5842)
			(stroke
				(width 0.1524)
				(type default)
			)
			(layer "F.SilkS")
		)
		(fp_line
			(start 1.7145 0.5842)
			(end 1.7145 -0.5842)
			(stroke
				(width 0.1524)
				(type default)
			)
			(layer "F.SilkS")
		)
		(fp_poly
			(pts
				(xy -1.27 -0.635) (xy 1.27 -0.635) (xy 1.27 0.635) (xy -1.27 0.635)
			)
			(stroke
				(width 0)
				(type default)
			)
			(fill yes)
			(layer "F.SilkS")
		)
		(fp_rect
			(start -1.9685 2.3622)
			(end 1.9685 -2.3622)
			(stroke
				(width 0)
				(type default)
			)
			(fill no)
			(layer "F.CrtYd")
		)
		(fp_poly
			(pts
				(xy -1.9685 -2.3622) (xy 1.9685 -2.3622) (xy 1.9685 2.3622) (xy -1.9685 2.3622)
			)
			(stroke
				(width 0)
				(type default)
			)
			(fill no)
			(layer "F.Fab")
		)
		(pad "1" smd rect
			(at -0.9525 1.3462)
			(size 0.5842 1.016)
			(layers "F.Cu" "F.Mask" "F.Paste")
			(net "P3V3_BS_NET")
		)
		(pad "2" smd rect
			(at 0 1.3462)
			(size 0.5842 1.016)
			(layers "F.Cu" "F.Mask" "F.Paste")
			(net "GND")
		)
		(pad "3" smd rect
			(at 0.9525 1.3462)
			(size 0.5842 1.016)
			(layers "F.Cu" "F.Mask" "F.Paste")
			(net "P3V3_FB")
		)
		(pad "4" smd rect
			(at 0.9525 -1.3462)
			(size 0.5842 1.016)
			(layers "F.Cu" "F.Mask" "F.Paste")
			(net "P3V3_EN")
		)
		(pad "5" smd rect
			(at 0 -1.3462)
			(size 0.5842 1.016)
			(layers "F.Cu" "F.Mask" "F.Paste")
			(net "P3V3_IN")
		)
		(pad "6" smd rect
			(at -0.9525 -1.3462)
			(size 0.5842 1.016)
			(layers "F.Cu" "F.Mask" "F.Paste")
			(net "P3V3_LX")
		)
	)
	(footprint ""
		(layer "F.Cu")
		(at 57.7342 -384.4036 90)
		(property "Reference" "R190"
			(at 0 0 90)
			(layer "F.SilkS")
			(hide yes)
			(effects
				(font
					(size 1.27 1.27)
				)
			)
		)
		(property "Value" "2R2010J-1-GP"
			(at 0.254 -8.0772 90)
			(unlocked yes)
			(layer "F.Fab")
			(hide yes)
			(effects
				(font
					(size 1.016 1.016)
					(thickness 0.1524)
				)
			)
		)
		(property "Device Type" "R2010H28"
			(at 0.254 -9.6774 90)
			(unlocked yes)
			(layer "F.Fab")
			(hide yes)
			(effects
				(font
					(size 1.016 1.016)
					(thickness 0.1524)
				)
			)
		)
		(duplicate_pad_numbers_are_jumpers no)
		(fp_line
			(start 1.651 -3.302)
			(end -1.651 -3.302)
			(stroke
				(width 0.1524)
				(type default)
			)
			(layer "F.SilkS")
		)
		(fp_line
			(start -1.651 -3.302)
			(end -1.651 3.302)
			(stroke
				(width 0.1524)
				(type default)
			)
			(layer "F.SilkS")
		)
		(fp_line
			(start 1.651 3.302)
			(end 1.651 -3.302)
			(stroke
				(width 0.1524)
				(type default)
			)
			(layer "F.SilkS")
		)
		(fp_line
			(start -1.651 3.302)
			(end 1.651 3.302)
			(stroke
				(width 0.1524)
				(type default)
			)
			(layer "F.SilkS")
		)
		(fp_rect
			(start -1.7272 -3.3782)
			(end 1.7272 3.3782)
			(stroke
				(width 0)
				(type default)
			)
			(fill no)
			(layer "F.CrtYd")
		)
		(fp_poly
			(pts
				(xy 1.7272 3.3782) (xy 1.7272 -3.3782) (xy -1.7272 -3.3782) (xy -1.7272 3.3782)
			)
			(stroke
				(width 0)
				(type default)
			)
			(fill no)
			(layer "F.Fab")
		)
		(pad "1" smd rect
			(at 0 -2.3495 90)
			(size 2.794 1.143)
			(layers "F.Cu" "F.Mask" "F.Paste")
			(net "5V_PRE_6")
		)
		(pad "2" smd rect
			(at 0 2.3495 90)
			(size 2.794 1.143)
			(layers "F.Cu" "F.Mask" "F.Paste")
			(net "P5V_HDD6")
		)
	)
	(footprint ""
		(layer "F.Cu")
		(at 75.692 -187.325 180)
		(property "Reference" "C229"
			(at 0 0 180)
			(layer "F.SilkS")
			(hide yes)
			(effects
				(font
					(size 1.27 1.27)
				)
			)
		)
		(property "Value" "SCD1U10V2KX-5GP"
			(at 1.1811 -2.7051 180)
			(unlocked yes)
			(layer "F.Fab")
			(hide yes)
			(effects
				(font
					(size 1.016 1.016)
					(thickness 0.1524)
				)
			)
		)
		(property "Device Type" "C402H22"
			(at 1.1811 -4.2291 180)
			(unlocked yes)
			(layer "F.Fab")
			(hide yes)
			(effects
				(font
					(size 1.016 1.016)
					(thickness 0.1524)
				)
			)
		)
		(duplicate_pad_numbers_are_jumpers no)
		(fp_rect
			(start -0.4318 0.9525)
			(end 0.4318 -0.9525)
			(stroke
				(width 0)
				(type default)
			)
			(fill no)
			(layer "F.CrtYd")
		)
		(fp_rect
			(start -0.4318 0.9525)
			(end 0.4318 -0.9525)
			(stroke
				(width 0)
				(type default)
			)
			(fill no)
			(layer "F.Fab")
		)
		(pad "1" smd custom
			(at 0 -0.4445 180)
			(size 0.1524 0.1524)
			(layers "F.Cu" "F.Mask" "F.Paste")
			(net "P3V3")
			(options
				(clearance outline)
				(anchor circle)
			)
			(primitives
				(gr_poly
					(pts
						(arc
							(start 0.3048 -0.2032)
							(mid 0.275042 -0.275042)
							(end 0.2032 -0.3048)
						)
						(arc
							(start -0.2032 -0.3048)
							(mid -0.275042 -0.275042)
							(end -0.3048 -0.2032)
						)
						(arc
							(start -0.3048 0.2032)
							(mid -0.275042 0.275042)
							(end -0.2032 0.3048)
						)
						(arc
							(start 0.2032 0.3048)
							(mid 0.275042 0.275042)
							(end 0.3048 0.2032)
						)
					)
					(width 0)
					(fill yes)
				)
			)
		)
		(pad "2" smd custom
			(at 0 0.4445 180)
			(size 0.1524 0.1524)
			(layers "F.Cu" "F.Mask" "F.Paste")
			(net "GND")
			(options
				(clearance outline)
				(anchor circle)
			)
			(primitives
				(gr_poly
					(pts
						(arc
							(start 0.3048 -0.2032)
							(mid 0.275042 -0.275042)
							(end 0.2032 -0.3048)
						)
						(arc
							(start -0.2032 -0.3048)
							(mid -0.275042 -0.275042)
							(end -0.3048 -0.2032)
						)
						(arc
							(start -0.3048 0.2032)
							(mid -0.275042 0.275042)
							(end -0.2032 0.3048)
						)
						(arc
							(start 0.2032 0.3048)
							(mid 0.275042 0.275042)
							(end 0.3048 0.2032)
						)
					)
					(width 0)
					(fill yes)
				)
			)
		)
	)
	(footprint ""
		(layer "F.Cu")
		(at 176.161446 -461.044036 180)
		(property "Reference" "C352"
			(at 0 0 180)
			(layer "F.SilkS")
			(hide yes)
			(effects
				(font
					(size 1.27 1.27)
				)
			)
		)
		(property "Value" "SCD1U16V2KX-3GP"
			(at 1.1811 -2.7051 180)
			(unlocked yes)
			(layer "F.Fab")
			(hide yes)
			(effects
				(font
					(size 1.016 1.016)
					(thickness 0.1524)
				)
			)
		)
		(property "Device Type" "C402H22"
			(at 1.1811 -4.2291 180)
			(unlocked yes)
			(layer "F.Fab")
			(hide yes)
			(effects
				(font
					(size 1.016 1.016)
					(thickness 0.1524)
				)
			)
		)
		(duplicate_pad_numbers_are_jumpers no)
		(fp_rect
			(start -0.4318 0.9525)
			(end 0.4318 -0.9525)
			(stroke
				(width 0)
				(type default)
			)
			(fill no)
			(layer "F.CrtYd")
		)
		(fp_rect
			(start -0.4318 0.9525)
			(end 0.4318 -0.9525)
			(stroke
				(width 0)
				(type default)
			)
			(fill no)
			(layer "F.Fab")
		)
		(pad "1" smd custom
			(at 0 -0.4445 180)
			(size 0.1524 0.1524)
			(layers "F.Cu" "F.Mask" "F.Paste")
			(net "P3V3")
			(options
				(clearance outline)
				(anchor circle)
			)
			(primitives
				(gr_poly
					(pts
						(arc
							(start 0.3048 -0.2032)
							(mid 0.275042 -0.275042)
							(end 0.2032 -0.3048)
						)
						(arc
							(start -0.2032 -0.3048)
							(mid -0.275042 -0.275042)
							(end -0.3048 -0.2032)
						)
						(arc
							(start -0.3048 0.2032)
							(mid -0.275042 0.275042)
							(end -0.2032 0.3048)
						)
						(arc
							(start 0.2032 0.3048)
							(mid 0.275042 0.275042)
							(end 0.3048 0.2032)
						)
					)
					(width 0)
					(fill yes)
				)
			)
		)
		(pad "2" smd custom
			(at 0 0.4445 180)
			(size 0.1524 0.1524)
			(layers "F.Cu" "F.Mask" "F.Paste")
			(net "GND")
			(options
				(clearance outline)
				(anchor circle)
			)
			(primitives
				(gr_poly
					(pts
						(arc
							(start 0.3048 -0.2032)
							(mid 0.275042 -0.275042)
							(end 0.2032 -0.3048)
						)
						(arc
							(start -0.2032 -0.3048)
							(mid -0.275042 -0.275042)
							(end -0.3048 -0.2032)
						)
						(arc
							(start -0.3048 0.2032)
							(mid -0.275042 0.275042)
							(end -0.2032 0.3048)
						)
						(arc
							(start 0.2032 0.3048)
							(mid 0.275042 0.275042)
							(end 0.3048 0.2032)
						)
					)
					(width 0)
					(fill yes)
				)
			)
		)
	)
	(footprint ""
		(layer "F.Cu")
		(at 25.79243 -235.709206 90)
		(property "Reference" "C297"
			(at 0 0 90)
			(layer "F.SilkS")
			(hide yes)
			(effects
				(font
					(size 1.27 1.27)
				)
			)
		)
		(property "Value" "SCD01U50V2KX-1GP"
			(at 1.1811 -2.7051 90)
			(unlocked yes)
			(layer "F.Fab")
			(hide yes)
			(effects
				(font
					(size 1.016 1.016)
					(thickness 0.1524)
				)
			)
		)
		(property "Device Type" "C402H22"
			(at 1.1811 -4.2291 90)
			(unlocked yes)
			(layer "F.Fab")
			(hide yes)
			(effects
				(font
					(size 1.016 1.016)
					(thickness 0.1524)
				)
			)
		)
		(duplicate_pad_numbers_are_jumpers no)
		(fp_rect
			(start -0.4318 0.9525)
			(end 0.4318 -0.9525)
			(stroke
				(width 0)
				(type default)
			)
			(fill no)
			(layer "F.CrtYd")
		)
		(fp_rect
			(start -0.4318 0.9525)
			(end 0.4318 -0.9525)
			(stroke
				(width 0)
				(type default)
			)
			(fill no)
			(layer "F.Fab")
		)
		(pad "1" smd custom
			(at 0 -0.4445 90)
			(size 0.1524 0.1524)
			(layers "F.Cu" "F.Mask" "F.Paste")
			(net "SAS2X28_DRIVE_RX_P_B12")
			(options
				(clearance outline)
				(anchor circle)
			)
			(primitives
				(gr_poly
					(pts
						(arc
							(start 0.3048 -0.2032)
							(mid 0.275042 -0.275042)
							(end 0.2032 -0.3048)
						)
						(arc
							(start -0.2032 -0.3048)
							(mid -0.275042 -0.275042)
							(end -0.3048 -0.2032)
						)
						(arc
							(start -0.3048 0.2032)
							(mid -0.275042 0.275042)
							(end -0.2032 0.3048)
						)
						(arc
							(start 0.2032 0.3048)
							(mid 0.275042 0.275042)
							(end 0.3048 0.2032)
						)
					)
					(width 0)
					(fill yes)
				)
			)
		)
		(pad "2" smd custom
			(at 0 0.4445 90)
			(size 0.1524 0.1524)
			(layers "F.Cu" "F.Mask" "F.Paste")
			(net "SAS2X28_B_HDD12_RX_+")
			(options
				(clearance outline)
				(anchor circle)
			)
			(primitives
				(gr_poly
					(pts
						(arc
							(start 0.3048 -0.2032)
							(mid 0.275042 -0.275042)
							(end 0.2032 -0.3048)
						)
						(arc
							(start -0.2032 -0.3048)
							(mid -0.275042 -0.275042)
							(end -0.3048 -0.2032)
						)
						(arc
							(start -0.3048 0.2032)
							(mid -0.275042 0.275042)
							(end -0.2032 0.3048)
						)
						(arc
							(start 0.2032 0.3048)
							(mid 0.275042 0.275042)
							(end 0.3048 0.2032)
						)
					)
					(width 0)
					(fill yes)
				)
			)
		)
	)
	(footprint ""
		(layer "F.Cu")
		(at 60.2742 -374.8532 -90)
		(property "Reference" "Q58"
			(at 0 0 270)
			(layer "F.SilkS")
			(hide yes)
			(effects
				(font
					(size 1.27 1.27)
				)
			)
		)
		(property "Value" "2N7002DW-7F-GP"
			(at -2.3622 -8.2042 270)
			(unlocked yes)
			(layer "F.Fab")
			(hide yes)
			(effects
				(font
					(size 1.016 1.016)
					(thickness 0.1524)
				)
			)
		)
		(property "Device Type" "SOT-363H44"
			(at -2.3622 -10.1092 270)
			(unlocked yes)
			(layer "F.Fab")
			(hide yes)
			(effects
				(font
					(size 1.016 1.016)
					(thickness 0.1524)
				)
			)
		)
		(duplicate_pad_numbers_are_jumpers no)
		(fp_line
			(start -1.4478 1.7018)
			(end 1.4478 1.7018)
			(stroke
				(width 0.1524)
				(type default)
			)
			(layer "F.SilkS")
		)
		(fp_line
			(start 1.4478 1.7018)
			(end 1.4478 -1.7018)
			(stroke
				(width 0.1524)
				(type default)
			)
			(layer "F.SilkS")
		)
		(fp_line
			(start -1.27 1.524)
			(end -1.27 0.6604)
			(stroke
				(width 0.4826)
				(type default)
			)
			(layer "F.SilkS")
		)
		(fp_line
			(start -1.4478 -1.7018)
			(end -1.4478 1.7018)
			(stroke
				(width 0.1524)
				(type default)
			)
			(layer "F.SilkS")
		)
		(fp_line
			(start 1.4478 -1.7018)
			(end -1.4478 -1.7018)
			(stroke
				(width 0.1524)
				(type default)
			)
			(layer "F.SilkS")
		)
		(fp_poly
			(pts
				(xy -1.524 -1.778) (xy 1.524 -1.778) (xy 1.524 1.778) (xy -1.524 1.778)
			)
			(stroke
				(width 0)
				(type default)
			)
			(fill no)
			(layer "F.CrtYd")
		)
		(fp_poly
			(pts
				(xy -1.524 -1.778) (xy 1.524 -1.778) (xy 1.524 1.778) (xy -1.524 1.778)
			)
			(stroke
				(width 0)
				(type default)
			)
			(fill no)
			(layer "F.Fab")
		)
		(pad "1" smd rect
			(at -0.65024 0.9398 270)
			(size 0.4064 1.016)
			(layers "F.Cu" "F.Mask" "F.Paste")
			(net "P3V3_HDD6_LED")
		)
		(pad "2" smd rect
			(at 0 0.9398 270)
			(size 0.4064 1.016)
			(layers "F.Cu" "F.Mask" "F.Paste")
			(net "HDD6_LED_G")
		)
		(pad "3" smd rect
			(at 0.65024 0.9398 270)
			(size 0.4064 1.016)
			(layers "F.Cu" "F.Mask" "F.Paste")
			(net "P5VB")
		)
		(pad "4" smd rect
			(at 0.65024 -0.9398 270)
			(size 0.4064 1.016)
			(layers "F.Cu" "F.Mask" "F.Paste")
			(net "P5VB_HDD6_LED")
		)
		(pad "5" smd rect
			(at 0 -0.9398 270)
			(size 0.4064 1.016)
			(layers "F.Cu" "F.Mask" "F.Paste")
			(net "HDD6_LED_G")
		)
		(pad "6" smd rect
			(at -0.65024 -0.9398 270)
			(size 0.4064 1.016)
			(layers "F.Cu" "F.Mask" "F.Paste")
			(net "P3V3")
		)
	)
	(footprint ""
		(layer "F.Cu")
		(at 57.3786 -79.4766 180)
		(property "Reference" "C251"
			(at 0 0 180)
			(layer "F.SilkS")
			(hide yes)
			(effects
				(font
					(size 1.27 1.27)
				)
			)
		)
		(property "Value" "SC10U16V6KX-2GP"
			(at -0.0762 -5.1308 180)
			(unlocked yes)
			(layer "F.Fab")
			(hide yes)
			(effects
				(font
					(size 1.016 1.016)
					(thickness 0.1524)
				)
			)
		)
		(property "Device Type" "C1206H71"
			(at -0.127 -6.6548 180)
			(unlocked yes)
			(layer "F.Fab")
			(hide yes)
			(effects
				(font
					(size 1.016 1.016)
					(thickness 0.1524)
				)
			)
		)
		(duplicate_pad_numbers_are_jumpers no)
		(fp_line
			(start 1.016 2.2352)
			(end -1.016 2.2352)
			(stroke
				(width 0.1524)
				(type default)
			)
			(layer "F.SilkS")
		)
		(fp_line
			(start 1.016 0.8382)
			(end 1.016 2.2352)
			(stroke
				(width 0.1524)
				(type default)
			)
			(layer "F.SilkS")
		)
		(fp_line
			(start 1.016 -2.2352)
			(end 1.016 -0.8382)
			(stroke
				(width 0.1524)
				(type default)
			)
			(layer "F.SilkS")
		)
		(fp_line
			(start -1.016 2.2352)
			(end -1.016 0.8382)
			(stroke
				(width 0.1524)
				(type default)
			)
			(layer "F.SilkS")
		)
		(fp_line
			(start -1.016 -0.8382)
			(end -1.016 -2.2352)
			(stroke
				(width 0.1524)
				(type default)
			)
			(layer "F.SilkS")
		)
		(fp_line
			(start -1.016 -2.2352)
			(end 1.016 -2.2352)
			(stroke
				(width 0.1524)
				(type default)
			)
			(layer "F.SilkS")
		)
		(fp_rect
			(start -1.0922 2.3114)
			(end 1.0922 -2.3114)
			(stroke
				(width 0)
				(type default)
			)
			(fill no)
			(layer "F.CrtYd")
		)
		(fp_poly
			(pts
				(xy 1.0922 -2.3114) (xy 1.0922 2.3114) (xy -1.0922 2.3114) (xy -1.0922 -2.3114)
			)
			(stroke
				(width 0)
				(type default)
			)
			(fill no)
			(layer "F.Fab")
		)
		(pad "1" smd rect
			(at 0 -1.397 180)
			(size 1.651 1.27)
			(layers "F.Cu" "F.Mask" "F.Paste")
			(net "P5V_HDD9")
		)
		(pad "2" smd rect
			(at 0 1.397 180)
			(size 1.651 1.27)
			(layers "F.Cu" "F.Mask" "F.Paste")
			(net "GND")
		)
	)
)
